# BASEBOARD_FAB2 (Tioga Pass) — schematic netlist excerpt (pin names and nets, part order shuffled) for the footprints in the layout excerpt that follows; sources: Cadence DE-HDL packaged netlist, KiCad conversion of Wiwynn_Tioga_Pass_MB.brd

C2T21  CAP_A  0.1UF 16V 10% X7R  pkg 0402V  page 185 : A = P3V3 ; B = GND
C25W37  CAP  1.0UF 16V 10% X6S  pkg 0402  page 149 : A = VCC_A_1V1 ; B = GND
C1R23  CAPP  68UF 16V 20% TANT  pkg 3018  page 195 : A = P12V_STBY ; B = GND

(kicad_pcb
	(version 20260206)
	(generator "pcbnew")
	(generator_version "10.0")
	(general
		(thickness 1.6)
		(legacy_teardrops no)
	)
	(paper "A4")
	(title_block
		(title "Wiwynn_Tioga_Pass_MB.brd")
		(comment 1 "Tioga Pass / footprints 2724-2726 of 4770")
	)
	(layers
		(0 "F.Cu" signal "TOP")
		(4 "In1.Cu" signal "L2GND")
		(6 "In2.Cu" signal "L3")
		(8 "In3.Cu" signal "L4GND")
		(10 "In4.Cu" signal "L5")
		(12 "In5.Cu" signal "L6GND")
		(14 "In6.Cu" signal "L7VCC")
		(16 "In7.Cu" signal "L8VCC")
		(18 "In8.Cu" signal "L9GND")
		(20 "In9.Cu" signal "L10")
		(22 "In10.Cu" signal "L11GND")
		(24 "In11.Cu" signal "L12")
		(26 "In12.Cu" signal "L13GND")
		(2 "B.Cu" signal "BOTTOM")
		(9 "F.Adhes" user "F.Adhesive")
		(11 "B.Adhes" user "B.Adhesive")
		(13 "F.Paste" user "Package Geometry/Pastemask Top")
		(15 "B.Paste" user "Package Geometry/Pastemask Bottom")
		(5 "F.SilkS" user "Ref Des/Silkscreen Top")
		(7 "B.SilkS" user "Ref Des/Silkscreen Bottom")
		(1 "F.Mask" user "Board Geometry/Soldermask Top")
		(3 "B.Mask" user "Board Geometry/Soldermask Bottom")
		(17 "Dwgs.User" user "User.Drawings")
		(19 "Cmts.User" user "User.Comments")
		(21 "Eco1.User" user "User.Eco1")
		(23 "Eco2.User" user "User.Eco2")
		(25 "Edge.Cuts" user "Board Geometry/Outline")
		(27 "Margin" user)
		(31 "F.CrtYd" user "Package Geometry/Place Bound Top")
		(29 "B.CrtYd" user "Package Geometry/Place Bound Bottom")
		(35 "F.Fab" user "Ref Des/Assembly Top")
		(33 "B.Fab" user "Ref Des/Assembly Bottom")
	)
	(footprint ""
		(layer "B.Cu")
		(at 390.635744 -24.169116 -90)
		(property "Reference" "C2T21"
			(at 0 0 90)
			(layer "B.SilkS")
			(hide yes)
			(effects
				(font
					(size 1.27 1.27)
				)
				(justify mirror)
			)
		)
		(property "Value" ""
			(at 0 0 90)
			(layer "B.Fab")
			(effects
				(font
					(size 1.27 1.27)
				)
				(justify mirror)
			)
		)
		(duplicate_pad_numbers_are_jumpers no)
		(fp_poly
			(pts
				(xy -0.3048 -0.1016) (xy -0.3048 0.9906) (xy 0.3048 0.9906) (xy 0.3048 -0.1016)
			)
			(stroke
				(width 0)
				(type default)
			)
			(fill no)
			(layer "B.CrtYd")
		)
		(fp_line
			(start -0.3048 0.9906)
			(end -0.3048 -0.1016)
			(stroke
				(width 0.1)
				(type default)
			)
			(layer "B.Fab")
		)
		(fp_line
			(start 0.3048 0.9906)
			(end -0.3048 0.9906)
			(stroke
				(width 0.1)
				(type default)
			)
			(layer "B.Fab")
		)
		(fp_line
			(start -0.3048 -0.1016)
			(end 0.3048 -0.1016)
			(stroke
				(width 0.1)
				(type default)
			)
			(layer "B.Fab")
		)
		(fp_line
			(start 0.3048 -0.1016)
			(end 0.3048 0.9906)
			(stroke
				(width 0.1)
				(type default)
			)
			(layer "B.Fab")
		)
		(pad "1" smd rect
			(at 0 0 90)
			(size 0.508 0.508)
			(layers "B.Cu" "B.Mask" "B.Paste")
			(net "P3V3")
		)
		(pad "2" smd rect
			(at 0 0.889 90)
			(size 0.508 0.508)
			(layers "B.Cu" "B.Mask" "B.Paste")
			(net "GND")
		)
		(zone
			(layer "B.Cu")
			(hatch none 0.5)
			(connect_pads
				(clearance 0)
			)
			(min_thickness 0.25)
			(keepout
				(tracks not_allowed)
				(vias allowed)
				(pads allowed)
				(copperpour not_allowed)
				(footprints allowed)
			)
			(placement
				(enabled no)
				(sheetname "")
			)
			(fill
				(thermal_gap 0.5)
				(thermal_bridge_width 0.5)
				(island_removal_mode 0)
			)
			(polygon
				(pts
					(xy 390.000744 -23.915116) (xy 390.000744 -24.423116) (xy 390.381744 -24.423116) (xy 390.381744 -23.915116)
				)
			)
		)
		(zone
			(layer "B.Cu")
			(hatch none 0.5)
			(connect_pads
				(clearance 0)
			)
			(min_thickness 0.25)
			(keepout
				(tracks allowed)
				(vias not_allowed)
				(pads allowed)
				(copperpour not_allowed)
				(footprints allowed)
			)
			(placement
				(enabled no)
				(sheetname "")
			)
			(fill
				(thermal_gap 0.5)
				(thermal_bridge_width 0.5)
				(island_removal_mode 0)
			)
			(polygon
				(pts
					(xy 390.381744 -23.915116) (xy 390.381744 -24.423116) (xy 390.000744 -24.423116) (xy 390.000744 -23.915116)
				)
			)
		)
	)
	(footprint ""
		(layer "B.Cu")
		(at 415.4805 -29.337 90)
		(property "Reference" "C25W37"
			(at 0.8382 -0.67818 90)
			(unlocked yes)
			(layer "B.SilkS")
			(effects
				(font
					(size 0.4064 0.254)
					(thickness 0.1524)
				)
				(justify left mirror)
			)
		)
		(property "Value" ""
			(at 0 0 90)
			(layer "B.Fab")
			(effects
				(font
					(size 1.27 1.27)
				)
				(justify mirror)
			)
		)
		(duplicate_pad_numbers_are_jumpers no)
		(fp_poly
			(pts
				(xy -0.3048 -0.1016) (xy -0.3048 0.9906) (xy 0.3048 0.9906) (xy 0.3048 -0.1016)
			)
			(stroke
				(width 0)
				(type default)
			)
			(fill no)
			(layer "B.CrtYd")
		)
		(fp_line
			(start 0.3048 -0.1016)
			(end 0.3048 0.9906)
			(stroke
				(width 0.1)
				(type default)
			)
			(layer "B.Fab")
		)
		(fp_line
			(start -0.3048 -0.1016)
			(end 0.3048 -0.1016)
			(stroke
				(width 0.1)
				(type default)
			)
			(layer "B.Fab")
		)
		(fp_line
			(start 0.3048 0.9906)
			(end -0.3048 0.9906)
			(stroke
				(width 0.1)
				(type default)
			)
			(layer "B.Fab")
		)
		(fp_line
			(start -0.3048 0.9906)
			(end -0.3048 -0.1016)
			(stroke
				(width 0.1)
				(type default)
			)
			(layer "B.Fab")
		)
		(pad "1" smd rect
			(at 0 0 270)
			(size 0.508 0.508)
			(layers "B.Cu" "B.Mask" "B.Paste")
			(net "VCC_A_1V1")
		)
		(pad "2" smd rect
			(at 0 0.889 270)
			(size 0.508 0.508)
			(layers "B.Cu" "B.Mask" "B.Paste")
			(net "GND")
		)
		(zone
			(layer "B.Cu")
			(hatch none 0.5)
			(connect_pads
				(clearance 0)
			)
			(min_thickness 0.25)
			(keepout
				(tracks allowed)
				(vias not_allowed)
				(pads allowed)
				(copperpour not_allowed)
				(footprints allowed)
			)
			(placement
				(enabled no)
				(sheetname "")
			)
			(fill
				(thermal_gap 0.5)
				(thermal_bridge_width 0.5)
				(island_removal_mode 0)
			)
			(polygon
				(pts
					(xy 415.7345 -29.591) (xy 415.7345 -29.083) (xy 416.1155 -29.083) (xy 416.1155 -29.591)
				)
			)
		)
		(zone
			(layer "B.Cu")
			(hatch none 0.5)
			(connect_pads
				(clearance 0)
			)
			(min_thickness 0.25)
			(keepout
				(tracks not_allowed)
				(vias allowed)
				(pads allowed)
				(copperpour not_allowed)
				(footprints allowed)
			)
			(placement
				(enabled no)
				(sheetname "")
			)
			(fill
				(thermal_gap 0.5)
				(thermal_bridge_width 0.5)
				(island_removal_mode 0)
			)
			(polygon
				(pts
					(xy 416.1155 -29.591) (xy 416.1155 -29.083) (xy 415.7345 -29.083) (xy 415.7345 -29.591)
				)
			)
		)
	)
	(footprint ""
		(layer "B.Cu")
		(at 482.53015 -22.163024 -90)
		(property "Reference" "C1R23"
			(at -3.25247 1.2954 180)
			(unlocked yes)
			(layer "B.SilkS")
			(effects
				(font
					(size 0.7874 0.5842)
					(thickness 0.1524)
				)
				(justify mirror)
			)
		)
		(property "Value" ""
			(at 0 0 90)
			(layer "B.Fab")
			(effects
				(font
					(size 1.27 1.27)
				)
				(justify mirror)
			)
		)
		(duplicate_pad_numbers_are_jumpers no)
		(fp_line
			(start -2.286 7.366)
			(end -1.600708 7.366)
			(stroke
				(width 0.1524)
				(type default)
			)
			(layer "B.SilkS")
		)
		(fp_line
			(start -2.286 7.366)
			(end -2.286 1.63195)
			(stroke
				(width 0.1524)
				(type default)
			)
			(layer "B.SilkS")
		)
		(fp_line
			(start 2.286 7.366)
			(end 1.60147 7.366)
			(stroke
				(width 0.1524)
				(type default)
			)
			(layer "B.SilkS")
		)
		(fp_line
			(start 2.286 7.366)
			(end 2.286 1.632712)
			(stroke
				(width 0.1524)
				(type default)
			)
			(layer "B.SilkS")
		)
		(fp_line
			(start -2.504948 1.633728)
			(end -1.6002 1.633728)
			(stroke
				(width 0.1524)
				(type default)
			)
			(layer "B.SilkS")
		)
		(fp_line
			(start 2.563114 1.633728)
			(end 1.6002 1.633728)
			(stroke
				(width 0.1524)
				(type default)
			)
			(layer "B.SilkS")
		)
		(fp_line
			(start -2.504948 -1.616456)
			(end -2.504948 1.633728)
			(stroke
				(width 0.1524)
				(type default)
			)
			(layer "B.SilkS")
		)
		(fp_line
			(start -1.6002 -1.616456)
			(end -2.504948 -1.616456)
			(stroke
				(width 0.1524)
				(type default)
			)
			(layer "B.SilkS")
		)
		(fp_line
			(start 1.6002 -1.616456)
			(end 2.563114 -1.616456)
			(stroke
				(width 0.1524)
				(type default)
			)
			(layer "B.SilkS")
		)
		(fp_line
			(start 2.563114 -1.616456)
			(end 2.563114 1.633728)
			(stroke
				(width 0.1524)
				(type default)
			)
			(layer "B.SilkS")
		)
		(fp_line
			(start -2.286 7.366)
			(end 2.286 7.366)
			(stroke
				(width 0.1)
				(type default)
			)
			(layer "B.Fab")
		)
		(fp_line
			(start 2.286 7.366)
			(end 2.286 -0.254)
			(stroke
				(width 0.1)
				(type default)
			)
			(layer "B.Fab")
		)
		(fp_line
			(start -2.286 -0.254)
			(end -2.286 7.366)
			(stroke
				(width 0.1)
				(type default)
			)
			(layer "B.Fab")
		)
		(fp_line
			(start 2.286 -0.254)
			(end -2.286 -0.254)
			(stroke
				(width 0.1)
				(type default)
			)
			(layer "B.Fab")
		)
		(pad "1" smd rect
			(at 0 0 90)
			(size 2.54 3.048)
			(layers "B.Cu" "B.Mask" "B.Paste")
			(net "P12V_STBY")
		)
		(pad "2" smd rect
			(at 0 7.112 90)
			(size 2.54 3.048)
			(layers "B.Cu" "B.Mask" "B.Paste")
			(net "GND")
		)
	)
)
